(kicad_pcb
	(version 20260206)
	(generator "pcbnew")
	(generator_version "10.0")
	(general
		(thickness 1.6)
		(legacy_teardrops no)
	)
	(paper "A4")
	(title_block
		(title "12092022_DA0F0TMDCD0_F0T_Management_Board_D_brd_V3_OCP.brd")
		(comment 1 "Grand Teton / footprints 342-347 of 1440")
	)
	(layers
		(0 "F.Cu" signal "TOP")
		(4 "In1.Cu" signal "GND")
		(6 "In2.Cu" signal "IN1")
		(8 "In3.Cu" signal "GND1")
		(10 "In4.Cu" signal "IN2")
		(12 "In5.Cu" signal "VCC")
		(14 "In6.Cu" signal "VCC1")
		(16 "In7.Cu" signal "IN3")
		(18 "In8.Cu" signal "GND2")
		(20 "In9.Cu" signal "IN4")
		(22 "In10.Cu" signal "GND3")
		(2 "B.Cu" signal "BOTTOM")
		(9 "F.Adhes" user "F.Adhesive")
		(11 "B.Adhes" user "B.Adhesive")
		(13 "F.Paste" user "Package Geometry/Pastemask Top")
		(15 "B.Paste" user "Package Geometry/Pastemask Bottom")
		(5 "F.SilkS" user "Ref Des/Silkscreen Top")
		(7 "B.SilkS" user "Ref Des/Silkscreen Bottom")
		(1 "F.Mask" user "Board Geometry/Soldermask Top")
		(3 "B.Mask" user "Board Geometry/Soldermask Bottom")
		(17 "Dwgs.User" user "User.Drawings")
		(19 "Cmts.User" user "User.Comments")
		(21 "Eco1.User" user "User.Eco1")
		(23 "Eco2.User" user "User.Eco2")
		(25 "Edge.Cuts" user "Board Geometry/Outline")
		(27 "Margin" user)
		(31 "F.CrtYd" user "Package Geometry/Place Bound Top")
		(29 "B.CrtYd" user "Package Geometry/Place Bound Bottom")
		(35 "F.Fab" user "Ref Des/Assembly Top")
		(33 "B.Fab" user "Ref Des/Assembly Bottom")
	)
	(footprint ""
		(layer "F.Cu")
		(at 79.685134 -59.059826 -90)
		(property "Reference" "PC258"
			(at 0 0 270)
			(layer "F.SilkS")
			(hide yes)
			(effects
				(font
					(size 1.27 1.27)
				)
			)
		)
		(property "Value" ""
			(at 0 0 270)
			(layer "F.Fab")
			(effects
				(font
					(size 1.27 1.27)
				)
			)
		)
		(duplicate_pad_numbers_are_jumpers no)
		(fp_line
			(start -1.651 0.8382)
			(end -1.651 -0.8382)
			(stroke
				(width 0.1524)
				(type default)
			)
			(layer "F.SilkS")
		)
		(fp_line
			(start 0 0.8382)
			(end 0 -0.8382)
			(stroke
				(width 0.1524)
				(type default)
			)
			(layer "F.SilkS")
		)
		(fp_line
			(start 1.651 0.8382)
			(end -1.651 0.8382)
			(stroke
				(width 0.1524)
				(type default)
			)
			(layer "F.SilkS")
		)
		(fp_line
			(start -1.651 -0.8382)
			(end 1.651 -0.8382)
			(stroke
				(width 0.1524)
				(type default)
			)
			(layer "F.SilkS")
		)
		(fp_line
			(start 1.651 -0.8382)
			(end 1.651 0.8382)
			(stroke
				(width 0.1524)
				(type default)
			)
			(layer "F.SilkS")
		)
		(fp_line
			(start -1.55956 0.7366)
			(end -1.524 0.7366)
			(stroke
				(width 0.1)
				(type default)
			)
			(layer "F.Fab")
		)
		(fp_line
			(start -1.524 0.7366)
			(end 1.524 0.7366)
			(stroke
				(width 0.1)
				(type default)
			)
			(layer "F.Fab")
		)
		(fp_line
			(start 1.524 0.7366)
			(end 1.55956 0.7366)
			(stroke
				(width 0.1)
				(type default)
			)
			(layer "F.Fab")
		)
		(fp_line
			(start 1.55956 0.7366)
			(end 1.55956 -0.7366)
			(stroke
				(width 0.1)
				(type default)
			)
			(layer "F.Fab")
		)
		(fp_line
			(start -1.55956 -0.7366)
			(end -1.55956 0.7366)
			(stroke
				(width 0.1)
				(type default)
			)
			(layer "F.Fab")
		)
		(fp_line
			(start -1.524 -0.7366)
			(end -1.55956 -0.7366)
			(stroke
				(width 0.1)
				(type default)
			)
			(layer "F.Fab")
		)
		(fp_line
			(start 1.524 -0.7366)
			(end -1.524 -0.7366)
			(stroke
				(width 0.1)
				(type default)
			)
			(layer "F.Fab")
		)
		(fp_line
			(start 1.55956 -0.7366)
			(end 1.524 -0.7366)
			(stroke
				(width 0.1)
				(type default)
			)
			(layer "F.Fab")
		)
		(pad "1" smd rect
			(at -0.94996 0 90)
			(size 1.1176 1.3716)
			(layers "F.Cu" "F.Mask" "F.Paste")
			(net "P1V2_AUX")
		)
		(pad "2" smd rect
			(at 0.94996 0 90)
			(size 1.1176 1.3716)
			(layers "F.Cu" "F.Mask" "F.Paste")
			(net "GND")
		)
	)
	(footprint ""
		(layer "F.Cu")
		(at 36.068 -44.5008 180)
		(property "Reference" "R710"
			(at 0 0 180)
			(layer "F.SilkS")
			(hide yes)
			(effects
				(font
					(size 1.27 1.27)
				)
			)
		)
		(property "Value" ""
			(at 0 0 180)
			(layer "F.Fab")
			(effects
				(font
					(size 1.27 1.27)
				)
			)
		)
		(duplicate_pad_numbers_are_jumpers no)
		(fp_line
			(start 0.7874 0.4064)
			(end -0.7874 0.4064)
			(stroke
				(width 0.1524)
				(type default)
			)
			(layer "F.SilkS")
		)
		(fp_line
			(start 0.7874 -0.4064)
			(end 0.7874 0.4064)
			(stroke
				(width 0.1524)
				(type default)
			)
			(layer "F.SilkS")
		)
		(fp_line
			(start -0.7874 0.4064)
			(end -0.7874 -0.4064)
			(stroke
				(width 0.1524)
				(type default)
			)
			(layer "F.SilkS")
		)
		(fp_line
			(start -0.7874 -0.4064)
			(end 0.7874 -0.4064)
			(stroke
				(width 0.1524)
				(type default)
			)
			(layer "F.SilkS")
		)
		(fp_line
			(start 0.67945 0.3048)
			(end 0.120396 0.3048)
			(stroke
				(width 0.1)
				(type default)
			)
			(layer "F.Fab")
		)
		(fp_line
			(start 0.67945 -0.3048)
			(end 0.67945 0.3048)
			(stroke
				(width 0.1)
				(type default)
			)
			(layer "F.Fab")
		)
		(fp_line
			(start 0.12065 -0.2794)
			(end 0.12065 -0.3048)
			(stroke
				(width 0.1)
				(type default)
			)
			(layer "F.Fab")
		)
		(fp_line
			(start 0.12065 -0.3048)
			(end 0.67945 -0.3048)
			(stroke
				(width 0.1)
				(type default)
			)
			(layer "F.Fab")
		)
		(fp_line
			(start 0.120396 0.3048)
			(end 0.120396 0.2794)
			(stroke
				(width 0.1)
				(type default)
			)
			(layer "F.Fab")
		)
		(fp_line
			(start 0.120396 0.2794)
			(end -0.12065 0.2794)
			(stroke
				(width 0.1)
				(type default)
			)
			(layer "F.Fab")
		)
		(fp_line
			(start -0.12065 0.3048)
			(end -0.67945 0.3048)
			(stroke
				(width 0.1)
				(type default)
			)
			(layer "F.Fab")
		)
		(fp_line
			(start -0.12065 0.2794)
			(end -0.12065 0.3048)
			(stroke
				(width 0.1)
				(type default)
			)
			(layer "F.Fab")
		)
		(fp_line
			(start -0.12065 -0.2794)
			(end 0.12065 -0.2794)
			(stroke
				(width 0.1)
				(type default)
			)
			(layer "F.Fab")
		)
		(fp_line
			(start -0.12065 -0.305054)
			(end -0.12065 -0.2794)
			(stroke
				(width 0.1)
				(type default)
			)
			(layer "F.Fab")
		)
		(fp_line
			(start -0.67945 0.3048)
			(end -0.67945 -0.305054)
			(stroke
				(width 0.1)
				(type default)
			)
			(layer "F.Fab")
		)
		(fp_line
			(start -0.67945 -0.305054)
			(end -0.12065 -0.305054)
			(stroke
				(width 0.1)
				(type default)
			)
			(layer "F.Fab")
		)
		(pad "1" smd circle
			(at -0.40005 0 180)
			(size 0 0)
			(layers "F.Cu" "F.Mask" "F.Paste")
			(net "P3V3_AUX")
		)
		(pad "2" smd circle
			(at 0.40005 0 180)
			(size 0 0)
			(layers "F.Cu" "F.Mask" "F.Paste")
			(net "U43_CT")
		)
	)
	(footprint ""
		(layer "F.Cu")
		(at 84.201 -95.631)
		(property "Reference" "R98"
			(at 0 0 0)
			(layer "F.SilkS")
			(hide yes)
			(effects
				(font
					(size 1.27 1.27)
				)
			)
		)
		(property "Value" ""
			(at 0 0 0)
			(layer "F.Fab")
			(effects
				(font
					(size 1.27 1.27)
				)
			)
		)
		(duplicate_pad_numbers_are_jumpers no)
		(fp_line
			(start -0.7874 -0.4064)
			(end 0.7874 -0.4064)
			(stroke
				(width 0.1524)
				(type default)
			)
			(layer "F.SilkS")
		)
		(fp_line
			(start -0.7874 0.4064)
			(end -0.7874 -0.4064)
			(stroke
				(width 0.1524)
				(type default)
			)
			(layer "F.SilkS")
		)
		(fp_line
			(start 0.7874 -0.4064)
			(end 0.7874 0.4064)
			(stroke
				(width 0.1524)
				(type default)
			)
			(layer "F.SilkS")
		)
		(fp_line
			(start 0.7874 0.4064)
			(end -0.7874 0.4064)
			(stroke
				(width 0.1524)
				(type default)
			)
			(layer "F.SilkS")
		)
		(fp_line
			(start -0.67945 -0.305054)
			(end -0.12065 -0.305054)
			(stroke
				(width 0.1)
				(type default)
			)
			(layer "F.Fab")
		)
		(fp_line
			(start -0.67945 0.3048)
			(end -0.67945 -0.305054)
			(stroke
				(width 0.1)
				(type default)
			)
			(layer "F.Fab")
		)
		(fp_line
			(start -0.12065 -0.305054)
			(end -0.12065 -0.2794)
			(stroke
				(width 0.1)
				(type default)
			)
			(layer "F.Fab")
		)
		(fp_line
			(start -0.12065 -0.2794)
			(end 0.12065 -0.2794)
			(stroke
				(width 0.1)
				(type default)
			)
			(layer "F.Fab")
		)
		(fp_line
			(start -0.12065 0.2794)
			(end -0.12065 0.3048)
			(stroke
				(width 0.1)
				(type default)
			)
			(layer "F.Fab")
		)
		(fp_line
			(start -0.12065 0.3048)
			(end -0.67945 0.3048)
			(stroke
				(width 0.1)
				(type default)
			)
			(layer "F.Fab")
		)
		(fp_line
			(start 0.120396 0.2794)
			(end -0.12065 0.2794)
			(stroke
				(width 0.1)
				(type default)
			)
			(layer "F.Fab")
		)
		(fp_line
			(start 0.120396 0.3048)
			(end 0.120396 0.2794)
			(stroke
				(width 0.1)
				(type default)
			)
			(layer "F.Fab")
		)
		(fp_line
			(start 0.12065 -0.3048)
			(end 0.67945 -0.3048)
			(stroke
				(width 0.1)
				(type default)
			)
			(layer "F.Fab")
		)
		(fp_line
			(start 0.12065 -0.2794)
			(end 0.12065 -0.3048)
			(stroke
				(width 0.1)
				(type default)
			)
			(layer "F.Fab")
		)
		(fp_line
			(start 0.67945 -0.3048)
			(end 0.67945 0.3048)
			(stroke
				(width 0.1)
				(type default)
			)
			(layer "F.Fab")
		)
		(fp_line
			(start 0.67945 0.3048)
			(end 0.120396 0.3048)
			(stroke
				(width 0.1)
				(type default)
			)
			(layer "F.Fab")
		)
		(pad "1" smd circle
			(at -0.40005 0)
			(size 0 0)
			(layers "F.Cu" "F.Mask" "F.Paste")
			(net "SPI_BMC_TPM_MISO_R")
		)
		(pad "2" smd circle
			(at 0.40005 0)
			(size 0 0)
			(layers "F.Cu" "F.Mask" "F.Paste")
			(net "SPI_BMC_TPM_MISO")
		)
	)
	(footprint ""
		(layer "F.Cu")
		(at 16.8275 -106.6165 -90)
		(property "Reference" "C147"
			(at 0 0 270)
			(layer "F.SilkS")
			(hide yes)
			(effects
				(font
					(size 1.27 1.27)
				)
			)
		)
		(property "Value" ""
			(at 0 0 270)
			(layer "F.Fab")
			(effects
				(font
					(size 1.27 1.27)
				)
			)
		)
		(duplicate_pad_numbers_are_jumpers no)
		(fp_line
			(start -0.7874 0.4064)
			(end -0.7874 -0.4064)
			(stroke
				(width 0.1524)
				(type default)
			)
			(layer "F.SilkS")
		)
		(fp_line
			(start 0.7874 0.4064)
			(end -0.7874 0.4064)
			(stroke
				(width 0.1524)
				(type default)
			)
			(layer "F.SilkS")
		)
		(fp_line
			(start -0.7874 -0.4064)
			(end 0.7874 -0.4064)
			(stroke
				(width 0.1524)
				(type default)
			)
			(layer "F.SilkS")
		)
		(fp_line
			(start 0.7874 -0.4064)
			(end 0.7874 0.4064)
			(stroke
				(width 0.1524)
				(type default)
			)
			(layer "F.SilkS")
		)
		(fp_line
			(start -0.67945 0.3048)
			(end -0.67945 -0.305054)
			(stroke
				(width 0.1)
				(type default)
			)
			(layer "F.Fab")
		)
		(fp_line
			(start -0.12065 0.3048)
			(end -0.67945 0.3048)
			(stroke
				(width 0.1)
				(type default)
			)
			(layer "F.Fab")
		)
		(fp_line
			(start 0.120396 0.3048)
			(end 0.120396 0.2794)
			(stroke
				(width 0.1)
				(type default)
			)
			(layer "F.Fab")
		)
		(fp_line
			(start 0.67945 0.3048)
			(end 0.120396 0.3048)
			(stroke
				(width 0.1)
				(type default)
			)
			(layer "F.Fab")
		)
		(fp_line
			(start -0.12065 0.2794)
			(end -0.12065 0.3048)
			(stroke
				(width 0.1)
				(type default)
			)
			(layer "F.Fab")
		)
		(fp_line
			(start 0.120396 0.2794)
			(end -0.12065 0.2794)
			(stroke
				(width 0.1)
				(type default)
			)
			(layer "F.Fab")
		)
		(fp_line
			(start -0.12065 -0.2794)
			(end 0.12065 -0.2794)
			(stroke
				(width 0.1)
				(type default)
			)
			(layer "F.Fab")
		)
		(fp_line
			(start 0.12065 -0.2794)
			(end 0.12065 -0.3048)
			(stroke
				(width 0.1)
				(type default)
			)
			(layer "F.Fab")
		)
		(fp_line
			(start 0.12065 -0.3048)
			(end 0.67945 -0.3048)
			(stroke
				(width 0.1)
				(type default)
			)
			(layer "F.Fab")
		)
		(fp_line
			(start 0.67945 -0.3048)
			(end 0.67945 0.3048)
			(stroke
				(width 0.1)
				(type default)
			)
			(layer "F.Fab")
		)
		(fp_line
			(start -0.67945 -0.305054)
			(end -0.12065 -0.305054)
			(stroke
				(width 0.1)
				(type default)
			)
			(layer "F.Fab")
		)
		(fp_line
			(start -0.12065 -0.305054)
			(end -0.12065 -0.2794)
			(stroke
				(width 0.1)
				(type default)
			)
			(layer "F.Fab")
		)
		(pad "1" smd circle
			(at -0.40005 0 270)
			(size 0 0)
			(layers "F.Cu" "F.Mask" "F.Paste")
			(net "P3V3_AUX")
		)
		(pad "2" smd circle
			(at 0.40005 0 270)
			(size 0 0)
			(layers "F.Cu" "F.Mask" "F.Paste")
			(net "GND")
		)
	)
	(footprint ""
		(layer "F.Cu")
		(at 59.6392 -81.1276 180)
		(property "Reference" "R509"
			(at 0 0 180)
			(layer "F.SilkS")
			(hide yes)
			(effects
				(font
					(size 1.27 1.27)
				)
			)
		)
		(property "Value" ""
			(at 0 0 180)
			(layer "F.Fab")
			(effects
				(font
					(size 1.27 1.27)
				)
			)
		)
		(duplicate_pad_numbers_are_jumpers no)
		(fp_line
			(start 0.7874 0.4064)
			(end -0.7874 0.4064)
			(stroke
				(width 0.1524)
				(type default)
			)
			(layer "F.SilkS")
		)
		(fp_line
			(start 0.7874 -0.4064)
			(end 0.7874 0.4064)
			(stroke
				(width 0.1524)
				(type default)
			)
			(layer "F.SilkS")
		)
		(fp_line
			(start -0.7874 0.4064)
			(end -0.7874 -0.4064)
			(stroke
				(width 0.1524)
				(type default)
			)
			(layer "F.SilkS")
		)
		(fp_line
			(start -0.7874 -0.4064)
			(end 0.7874 -0.4064)
			(stroke
				(width 0.1524)
				(type default)
			)
			(layer "F.SilkS")
		)
		(fp_line
			(start 0.67945 0.3048)
			(end 0.120396 0.3048)
			(stroke
				(width 0.1)
				(type default)
			)
			(layer "F.Fab")
		)
		(fp_line
			(start 0.67945 -0.3048)
			(end 0.67945 0.3048)
			(stroke
				(width 0.1)
				(type default)
			)
			(layer "F.Fab")
		)
		(fp_line
			(start 0.12065 -0.2794)
			(end 0.12065 -0.3048)
			(stroke
				(width 0.1)
				(type default)
			)
			(layer "F.Fab")
		)
		(fp_line
			(start 0.12065 -0.3048)
			(end 0.67945 -0.3048)
			(stroke
				(width 0.1)
				(type default)
			)
			(layer "F.Fab")
		)
		(fp_line
			(start 0.120396 0.3048)
			(end 0.120396 0.2794)
			(stroke
				(width 0.1)
				(type default)
			)
			(layer "F.Fab")
		)
		(fp_line
			(start 0.120396 0.2794)
			(end -0.12065 0.2794)
			(stroke
				(width 0.1)
				(type default)
			)
			(layer "F.Fab")
		)
		(fp_line
			(start -0.12065 0.3048)
			(end -0.67945 0.3048)
			(stroke
				(width 0.1)
				(type default)
			)
			(layer "F.Fab")
		)
		(fp_line
			(start -0.12065 0.2794)
			(end -0.12065 0.3048)
			(stroke
				(width 0.1)
				(type default)
			)
			(layer "F.Fab")
		)
		(fp_line
			(start -0.12065 -0.2794)
			(end 0.12065 -0.2794)
			(stroke
				(width 0.1)
				(type default)
			)
			(layer "F.Fab")
		)
		(fp_line
			(start -0.12065 -0.305054)
			(end -0.12065 -0.2794)
			(stroke
				(width 0.1)
				(type default)
			)
			(layer "F.Fab")
		)
		(fp_line
			(start -0.67945 0.3048)
			(end -0.67945 -0.305054)
			(stroke
				(width 0.1)
				(type default)
			)
			(layer "F.Fab")
		)
		(fp_line
			(start -0.67945 -0.305054)
			(end -0.12065 -0.305054)
			(stroke
				(width 0.1)
				(type default)
			)
			(layer "F.Fab")
		)
		(pad "1" smd circle
			(at -0.40005 0 180)
			(size 0 0)
			(layers "F.Cu" "F.Mask" "F.Paste")
			(net "MB_JTAG_PLD_R_JTAGEN")
		)
		(pad "2" smd circle
			(at 0.40005 0 180)
			(size 0 0)
			(layers "F.Cu" "F.Mask" "F.Paste")
			(net "JTAG_SCM_PLD_JTAGEN")
		)
	)
	(footprint ""
		(layer "F.Cu")
		(at 38.6334 -109.8804)
		(property "Reference" "R76"
			(at 0 0 0)
			(layer "F.SilkS")
			(hide yes)
			(effects
				(font
					(size 1.27 1.27)
				)
			)
		)
		(property "Value" ""
			(at 0 0 0)
			(layer "F.Fab")
			(effects
				(font
					(size 1.27 1.27)
				)
			)
		)
		(duplicate_pad_numbers_are_jumpers no)
		(fp_line
			(start -0.7874 -0.4064)
			(end 0.7874 -0.4064)
			(stroke
				(width 0.1524)
				(type default)
			)
			(layer "F.SilkS")
		)
		(fp_line
			(start -0.7874 0.4064)
			(end -0.7874 -0.4064)
			(stroke
				(width 0.1524)
				(type default)
			)
			(layer "F.SilkS")
		)
		(fp_line
			(start 0.7874 -0.4064)
			(end 0.7874 0.4064)
			(stroke
				(width 0.1524)
				(type default)
			)
			(layer "F.SilkS")
		)
		(fp_line
			(start 0.7874 0.4064)
			(end -0.7874 0.4064)
			(stroke
				(width 0.1524)
				(type default)
			)
			(layer "F.SilkS")
		)
		(fp_line
			(start -0.67945 -0.305054)
			(end -0.12065 -0.305054)
			(stroke
				(width 0.1)
				(type default)
			)
			(layer "F.Fab")
		)
		(fp_line
			(start -0.67945 0.3048)
			(end -0.67945 -0.305054)
			(stroke
				(width 0.1)
				(type default)
			)
			(layer "F.Fab")
		)
		(fp_line
			(start -0.12065 -0.305054)
			(end -0.12065 -0.2794)
			(stroke
				(width 0.1)
				(type default)
			)
			(layer "F.Fab")
		)
		(fp_line
			(start -0.12065 -0.2794)
			(end 0.12065 -0.2794)
			(stroke
				(width 0.1)
				(type default)
			)
			(layer "F.Fab")
		)
		(fp_line
			(start -0.12065 0.2794)
			(end -0.12065 0.3048)
			(stroke
				(width 0.1)
				(type default)
			)
			(layer "F.Fab")
		)
		(fp_line
			(start -0.12065 0.3048)
			(end -0.67945 0.3048)
			(stroke
				(width 0.1)
				(type default)
			)
			(layer "F.Fab")
		)
		(fp_line
			(start 0.120396 0.2794)
			(end -0.12065 0.2794)
			(stroke
				(width 0.1)
				(type default)
			)
			(layer "F.Fab")
		)
		(fp_line
			(start 0.120396 0.3048)
			(end 0.120396 0.2794)
			(stroke
				(width 0.1)
				(type default)
			)
			(layer "F.Fab")
		)
		(fp_line
			(start 0.12065 -0.3048)
			(end 0.67945 -0.3048)
			(stroke
				(width 0.1)
				(type default)
			)
			(layer "F.Fab")
		)
		(fp_line
			(start 0.12065 -0.2794)
			(end 0.12065 -0.3048)
			(stroke
				(width 0.1)
				(type default)
			)
			(layer "F.Fab")
		)
		(fp_line
			(start 0.67945 -0.3048)
			(end 0.67945 0.3048)
			(stroke
				(width 0.1)
				(type default)
			)
			(layer "F.Fab")
		)
		(fp_line
			(start 0.67945 0.3048)
			(end 0.120396 0.3048)
			(stroke
				(width 0.1)
				(type default)
			)
			(layer "F.Fab")
		)
		(pad "1" smd circle
			(at -0.40005 0)
			(size 0 0)
			(layers "F.Cu" "F.Mask" "F.Paste")
			(net "P3V3_AUX")
		)
		(pad "2" smd circle
			(at 0.40005 0)
			(size 0 0)
			(layers "F.Cu" "F.Mask" "F.Paste")
			(net "SGPIO_CLK_1")
		)
	)
)
